# SCM (Grand Teton) — schematic netlist excerpt (pin names and nets, part order shuffled) for the footprints in the layout excerpt that follows; sources: Cadence DE-HDL packaged netlist, KiCad conversion of 12092022_DA0F0TMDCD0_F0T_Management_Board_D_brd_V3_OCP.brd

J29  PICOPROBE_BXA  DELTA-L 4.0 EMPTY  pkg TRIANG_LAUNCH_3PXB  page 58
  \1_p\  = 85_5INCH_IN1_DP
  \2_n\  = 85_5INCH_IN1_DN
  \3_g\  = GND_P1

(kicad_pcb
	(version 20260206)
	(generator "pcbnew")
	(generator_version "10.0")
	(general
		(thickness 1.6)
		(legacy_teardrops no)
	)
	(paper "A4")
	(title_block
		(title "12092022_DA0F0TMDCD0_F0T_Management_Board_D_brd_V3_OCP.brd")
		(comment 1 "Grand Teton / footprints 868-868 of 1440")
	)
	(layers
		(0 "F.Cu" signal "TOP")
		(4 "In1.Cu" signal "GND")
		(6 "In2.Cu" signal "IN1")
		(8 "In3.Cu" signal "GND1")
		(10 "In4.Cu" signal "IN2")
		(12 "In5.Cu" signal "VCC")
		(14 "In6.Cu" signal "VCC1")
		(16 "In7.Cu" signal "IN3")
		(18 "In8.Cu" signal "GND2")
		(20 "In9.Cu" signal "IN4")
		(22 "In10.Cu" signal "GND3")
		(2 "B.Cu" signal "BOTTOM")
		(9 "F.Adhes" user "F.Adhesive")
		(11 "B.Adhes" user "B.Adhesive")
		(13 "F.Paste" user "Package Geometry/Pastemask Top")
		(15 "B.Paste" user "Package Geometry/Pastemask Bottom")
		(5 "F.SilkS" user "Ref Des/Silkscreen Top")
		(7 "B.SilkS" user "Ref Des/Silkscreen Bottom")
		(1 "F.Mask" user "Board Geometry/Soldermask Top")
		(3 "B.Mask" user "Board Geometry/Soldermask Bottom")
		(17 "Dwgs.User" user "User.Drawings")
		(19 "Cmts.User" user "User.Comments")
		(21 "Eco1.User" user "User.Eco1")
		(23 "Eco2.User" user "User.Eco2")
		(25 "Edge.Cuts" user "Board Geometry/Outline")
		(27 "Margin" user)
		(31 "F.CrtYd" user "Package Geometry/Place Bound Top")
		(29 "B.CrtYd" user "Package Geometry/Place Bound Bottom")
		(35 "F.Fab" user "Ref Des/Assembly Top")
		(33 "B.Fab" user "Ref Des/Assembly Bottom")
	)
	(footprint ""
		(layer "B.Cu")
		(at 95.911416 112.766602 -90)
		(property "Reference" "J29"
			(at 6.105398 -1.470914 270)
			(unlocked yes)
			(layer "B.SilkS")
			(effects
				(font
					(size 0.7874 0.5842)
					(thickness 0.1524)
				)
				(justify left mirror)
			)
		)
		(property "Value" ""
			(at 0 0 90)
			(layer "B.Fab")
			(effects
				(font
					(size 1.27 1.27)
				)
				(justify mirror)
			)
		)
		(duplicate_pad_numbers_are_jumpers no)
		(fp_line
			(start -1.2192 2.1082)
			(end 1.2192 2.1082)
			(stroke
				(width 0.1524)
				(type default)
			)
			(layer "B.SilkS")
		)
		(fp_line
			(start 1.2192 2.1082)
			(end 1.2192 -2.1082)
			(stroke
				(width 0.1524)
				(type default)
			)
			(layer "B.SilkS")
		)
		(fp_line
			(start -1.2192 0.813562)
			(end -1.2192 2.1082)
			(stroke
				(width 0.1524)
				(type default)
			)
			(layer "B.SilkS")
		)
		(fp_line
			(start -1.2192 -2.1082)
			(end -1.2192 -0.82677)
			(stroke
				(width 0.1524)
				(type default)
			)
			(layer "B.SilkS")
		)
		(fp_line
			(start 1.2192 -2.1082)
			(end -1.2192 -2.1082)
			(stroke
				(width 0.1524)
				(type default)
			)
			(layer "B.SilkS")
		)
		(pad "" np_thru_hole circle
			(at -3.4671 -1.27 180)
			(size 1.0414 1.0414)
			(drill 1.0414)
			(layers "*.Cu" "*.Mask")
			(clearance 0.381)
			(thermal_gap 0.381)
		)
		(pad "" np_thru_hole circle
			(at -3.4671 1.27 180)
			(size 1.0414 1.0414)
			(drill 1.0414)
			(layers "*.Cu" "*.Mask")
			(clearance 0.381)
			(thermal_gap 0.381)
		)
		(pad "" np_thru_hole circle
			(at 2.8829 -1.27 180)
			(size 1.0414 1.0414)
			(drill 1.0414)
			(layers "*.Cu" "*.Mask")
			(clearance 0.381)
			(thermal_gap 0.381)
		)
		(pad "" np_thru_hole circle
			(at 2.8829 1.27 180)
			(size 1.0414 1.0414)
			(drill 1.0414)
			(layers "*.Cu" "*.Mask")
			(clearance 0.381)
			(thermal_gap 0.381)
		)
		(pad "1" smd rect
			(at -0.8255 -0.249936 180)
			(size 0.3048 0.508)
			(layers "B.Cu" "B.Mask" "B.Paste")
			(net "85_5INCH_IN1_DP")
		)
		(pad "2" smd rect
			(at -0.8255 0.249936 180)
			(size 0.3048 0.508)
			(layers "B.Cu" "B.Mask" "B.Paste")
			(net "85_5INCH_IN1_DN")
		)
		(pad "3" smd circle
			(at 0 0 90)
			(size 0 0)
			(layers "B.Cu" "B.Mask" "B.Paste")
			(net "GND_P1")
		)
		(zone
			(layers "F.Cu" "B.Cu" "In1.Cu" "In2.Cu" "In3.Cu" "In4.Cu" "In5.Cu" "In6.Cu"
				"In7.Cu" "In8.Cu" "In9.Cu" "In10.Cu"
			)
			(hatch none 0.5)
			(connect_pads
				(clearance 0)
			)
			(min_thickness 0.25)
			(keepout
				(tracks not_allowed)
				(vias allowed)
				(pads allowed)
				(copperpour not_allowed)
				(footprints allowed)
			)
			(placement
				(enabled no)
				(sheetname "")
			)
			(fill
				(thermal_gap 0.5)
				(thermal_bridge_width 0.5)
				(island_removal_mode 0)
			)
			(polygon
				(pts
					(arc
						(start 95.568516 109.299502)
						(mid 93.714316 109.299502)
						(end 95.568516 109.299502)
					)
				)
			)
		)
		(zone
			(layers "F.Cu" "B.Cu" "In1.Cu" "In2.Cu" "In3.Cu" "In4.Cu" "In5.Cu" "In6.Cu"
				"In7.Cu" "In8.Cu" "In9.Cu" "In10.Cu"
			)
			(hatch none 0.5)
			(connect_pads
				(clearance 0)
			)
			(min_thickness 0.25)
			(keepout
				(tracks not_allowed)
				(vias allowed)
				(pads allowed)
				(copperpour not_allowed)
				(footprints allowed)
			)
			(placement
				(enabled no)
				(sheetname "")
			)
			(fill
				(thermal_gap 0.5)
				(thermal_bridge_width 0.5)
				(island_removal_mode 0)
			)
			(polygon
				(pts
					(arc
						(start 95.568516 115.649502)
						(mid 93.714316 115.649502)
						(end 95.568516 115.649502)
					)
				)
			)
		)
		(zone
			(layers "F.Cu" "B.Cu" "In1.Cu" "In2.Cu" "In3.Cu" "In4.Cu" "In5.Cu" "In6.Cu"
				"In7.Cu" "In8.Cu" "In9.Cu" "In10.Cu"
			)
			(hatch none 0.5)
			(connect_pads
				(clearance 0)
			)
			(min_thickness 0.25)
			(keepout
				(tracks not_allowed)
				(vias allowed)
				(pads allowed)
				(copperpour not_allowed)
				(footprints allowed)
			)
			(placement
				(enabled no)
				(sheetname "")
			)
			(fill
				(thermal_gap 0.5)
				(thermal_bridge_width 0.5)
				(island_removal_mode 0)
			)
			(polygon
				(pts
					(arc
						(start 98.108516 109.299502)
						(mid 96.254316 109.299502)
						(end 98.108516 109.299502)
					)
				)
			)
		)
		(zone
			(layers "F.Cu" "B.Cu" "In1.Cu" "In2.Cu" "In3.Cu" "In4.Cu" "In5.Cu" "In6.Cu"
				"In7.Cu" "In8.Cu" "In9.Cu" "In10.Cu"
			)
			(hatch none 0.5)
			(connect_pads
				(clearance 0)
			)
			(min_thickness 0.25)
			(keepout
				(tracks not_allowed)
				(vias allowed)
				(pads allowed)
				(copperpour not_allowed)
				(footprints allowed)
			)
			(placement
				(enabled no)
				(sheetname "")
			)
			(fill
				(thermal_gap 0.5)
				(thermal_bridge_width 0.5)
				(island_removal_mode 0)
			)
			(polygon
				(pts
					(arc
						(start 98.108516 115.649502)
						(mid 96.254316 115.649502)
						(end 98.108516 115.649502)
					)
				)
			)
		)
		(zone
			(layer "B.Cu")
			(hatch none 0.5)
			(connect_pads
				(clearance 0)
			)
			(min_thickness 0.25)
			(keepout
				(tracks not_allowed)
				(vias allowed)
				(pads allowed)
				(copperpour not_allowed)
				(footprints allowed)
			)
			(placement
				(enabled no)
				(sheetname "")
			)
			(fill
				(thermal_gap 0.5)
				(thermal_bridge_width 0.5)
				(island_removal_mode 0)
			)
			(polygon
				(pts
					(xy 96.460056 111.649002) (xy 96.364552 111.649002) (xy 96.364552 112.245902) (xy 95.958152 112.245902)
					(xy 95.958152 111.649002) (xy 95.86468 111.649002) (xy 95.86468 112.245902) (xy 95.45828 112.245902)
					(xy 95.45828 111.649002) (xy 95.362776 111.649002) (xy 95.362776 112.347502) (xy 96.460056 112.347502)
				)
			)
		)
	)
)
